FILE_TYPE = CONNECTIVITY;
{Allegro Design Entry HDL 17.4-2019 S026 (4007227) 1/17/2022}
"PAGE_NUMBER" = 450;
0"NC";
1"P5E_CPU1_P2_TX_BUF_DN<7:0>";
2"P5E_CPU1_P2_TX_BUF_C_DN<7:0>";
3"P5E_CPU1_P2_TX_BUF_DP<7:0>";
4"P5E_CPU1_P2_TX_BUF_C_DP<7:0>";
5"P5E_CPU1_P2_TX_BUF_DN<15:8>";
6"P5E_CPU1_P2_TX_BUF_DP<15:8>";
7"P5E_CPU1_P2_TX_BUF_C_DN<15:8>";
8"P5E_CPU1_P2_TX_BUF_C_DP<15:8>";
9"P5E_CPU1_P2_TX_BUF_DN<15:8>";
10"P5E_CPU1_P2_TX_BUF_DN<7:0>";
11"P5E_CPU1_P2_TX_BUF_DP<7:0>";
12"P5E_CPU1_P2_TX_BUF_DP<15:8>";
13"P5E_CPU1_P2_TX_BUF_DP<9>";
14"P5E_CPU1_P2_TX_BUF_DP<10>";
15"P5E_CPU1_P2_TX_BUF_DN<10>";
16"P5E_CPU1_P2_TX_BUF_DN<9>";
17"P5E_CPU1_P2_TX_BUF_DP<12>";
18"P5E_CPU1_P2_TX_BUF_DN<11>";
19"P5E_CPU1_P2_TX_BUF_DP<14>";
20"P5E_CPU1_P2_TX_BUF_DP<15>";
21"P5E_CPU1_P2_TX_BUF_DP<1>";
22"P5E_CPU1_P2_TX_BUF_DP<3>";
23"P5E_CPU1_P2_TX_BUF_DP<5>";
24"P5E_CPU1_P2_TX_BUF_DP<4>";
25"P5E_CPU1_P2_TX_BUF_DN<3>";
26"P5E_CPU1_P2_TX_BUF_DN<4>";
27"P5E_CPU1_P2_TX_BUF_DP<7>";
28"P5E_CPU1_P2_TX_BUF_DN<7>";
29"P5E_CPU1_P2_TX_BUF_DN<6>";
30"P5E_CPU1_P2_TX_BUF_DP<2>";
31"P5E_CPU1_P2_TX_BUF_DP<11>";
32"P5E_CPU1_P2_TX_BUF_DP<6>";
33"P5E_CPU1_P2_TX_BUF_DN<5>";
34"P5E_CPU1_P2_TX_BUF_DN<15>";
35"P5E_CPU1_P2_TX_BUF_DP<8>";
36"P5E_CPU1_P2_TX_BUF_DN<12>";
37"P5E_CPU1_P2_TX_BUF_DN<13>";
38"P5E_CPU1_P2_TX_BUF_DP<13>";
39"P5E_CPU1_P2_TX_BUF_DN<14>";
40"P5E_CPU1_P2_TX_BUF_DP<0>";
41"P5E_CPU1_P2_TX_BUF_DN<1>";
42"P5E_CPU1_P2_TX_BUF_DN<2>";
43"P5E_CPU1_P2_TX_BUF_DN<0>";
44"P5E_CPU1_P2_TX_BUF_DN<8>";
45"P5E_CPU1_P2_TX_BUF_C_DP<8>";
46"P5E_CPU1_P2_TX_BUF_C_DN<8>";
47"P5E_CPU1_P2_TX_BUF_DP<8>";
48"P5E_CPU1_P2_TX_BUF_DN<8>";
49"P5E_CPU1_P2_TX_BUF_C_DP<9>";
50"P5E_CPU1_P2_TX_BUF_C_DN<9>";
51"P5E_CPU1_P2_TX_BUF_C_DP<10>";
52"P5E_CPU1_P2_TX_BUF_C_DN<10>";
53"P5E_CPU1_P2_TX_BUF_C_DP<11>";
54"P5E_CPU1_P2_TX_BUF_C_DN<11>";
55"P5E_CPU1_P2_TX_BUF_C_DP<12>";
56"P5E_CPU1_P2_TX_BUF_C_DN<12>";
57"P5E_CPU1_P2_TX_BUF_C_DP<13>";
58"P5E_CPU1_P2_TX_BUF_C_DN<13>";
59"P5E_CPU1_P2_TX_BUF_C_DP<14>";
60"P5E_CPU1_P2_TX_BUF_C_DN<14>";
61"P5E_CPU1_P2_TX_BUF_C_DP<15>";
62"P5E_CPU1_P2_TX_BUF_C_DN<15>";
63"P5E_CPU1_P2_TX_BUF_DP<9>";
64"P5E_CPU1_P2_TX_BUF_DP<10>";
65"P5E_CPU1_P2_TX_BUF_DP<11>";
66"P5E_CPU1_P2_TX_BUF_DN<9>";
67"P5E_CPU1_P2_TX_BUF_DN<11>";
68"P5E_CPU1_P2_TX_BUF_DN<10>";
69"P5E_CPU1_P2_TX_BUF_DP<12>";
70"P5E_CPU1_P2_TX_BUF_DP<13>";
71"P5E_CPU1_P2_TX_BUF_DN<13>";
72"P5E_CPU1_P2_TX_BUF_DN<12>";
73"P5E_CPU1_P2_TX_BUF_DP<14>";
74"P5E_CPU1_P2_TX_BUF_DP<15>";
75"P5E_CPU1_P2_TX_BUF_DN<14>";
76"P5E_CPU1_P2_TX_BUF_DN<15>";
77"P5E_CPU1_P2_TX_BUF_C_DP<0>";
78"P5E_CPU1_P2_TX_BUF_C_DN<0>";
79"P5E_CPU1_P2_TX_BUF_C_DP<1>";
80"P5E_CPU1_P2_TX_BUF_C_DN<1>";
81"P5E_CPU1_P2_TX_BUF_C_DP<2>";
82"P5E_CPU1_P2_TX_BUF_C_DP<3>";
83"P5E_CPU1_P2_TX_BUF_C_DN<3>";
84"P5E_CPU1_P2_TX_BUF_C_DP<4>";
85"P5E_CPU1_P2_TX_BUF_C_DN<4>";
86"P5E_CPU1_P2_TX_BUF_DP<0>";
87"P5E_CPU1_P2_TX_BUF_DP<1>";
88"P5E_CPU1_P2_TX_BUF_DP<2>";
89"P5E_CPU1_P2_TX_BUF_DP<3>";
90"P5E_CPU1_P2_TX_BUF_DP<4>";
91"P5E_CPU1_P2_TX_BUF_C_DP<5>";
92"P5E_CPU1_P2_TX_BUF_C_DN<5>";
93"P5E_CPU1_P2_TX_BUF_C_DP<6>";
94"P5E_CPU1_P2_TX_BUF_C_DN<6>";
95"P5E_CPU1_P2_TX_BUF_C_DP<7>";
96"P5E_CPU1_P2_TX_BUF_C_DN<7>";
97"P5E_CPU1_P2_TX_BUF_DP<5>";
98"P5E_CPU1_P2_TX_BUF_DP<6>";
99"P5E_CPU1_P2_TX_BUF_DP<7>";
100"P5E_CPU1_P2_TX_BUF_DN<1>";
101"P5E_CPU1_P2_TX_BUF_DN<2>";
102"P5E_CPU1_P2_TX_BUF_DN<3>";
103"P5E_CPU1_P2_TX_BUF_DN<4>";
104"P5E_CPU1_P2_TX_BUF_DN<5>";
105"P5E_CPU1_P2_TX_BUF_DN<6>";
106"P5E_CPU1_P2_TX_BUF_DN<7>";
107"P5E_CPU1_P2_TX_BUF_C_DN<2>";
108"P5E_CPU1_P2_TX_BUF_DN<0>";
%"TAP"
"1","(-3050,1375)","2","standard","I10";
;
CDS_LIB"standard"
BODY_TYPE"PLUMBING"
HDL_TAP"TRUE";
"B \NAC \NWC"3;
"S \NAC"
BN"4"90;
%"TAP"
"1","(-8075,2200)","2","standard","I100";
;
CDS_LIB"standard"
BODY_TYPE"PLUMBING"
HDL_TAP"TRUE";
"B \NAC \NWC"5;
"S \NAC"
BN"8"48;
%"TAP"
"1","(-7825,2250)","2","standard","I101";
;
CDS_LIB"standard"
BODY_TYPE"PLUMBING"
HDL_TAP"TRUE";
"B \NAC \NWC"6;
"S \NAC"
BN"8"47;
%"Q_CAP_DIFFBUS"
"2","(-7100,2250)","2","pure_quanta","I102";
;
LOCATION"C6709"
$SEC"1"
CDS_SEC"1"
VALUE"DIFF BUS_0.22UF"
VOLTAGE"6.3V"
MATERIAL"X6S"
PACK_TYPE"C0201"
TOLERANCE"20%"
CDS_LIB"pure_quanta"
CDS_LMAN_SYM_OUTLINE"-25,50,25,-50"
PIN_NAMES_ROTATE"TRUE"
PART_NUMBER"SP_CH4221MEE01"
LOCATION"C6709";
"2"
$PN"2"47;
"1"
$PN"1"45;
%"Q_CAP_DIFFBUS"
"2","(-7100,2200)","2","pure_quanta","I103";
;
LOCATION"C6710"
$SEC"1"
CDS_SEC"1"
VALUE"DIFF BUS_0.22UF"
CDS_LMAN_SYM_OUTLINE"-25,50,25,-50"
CDS_LIB"pure_quanta"
PIN_NAMES_ROTATE"TRUE"
VOLTAGE"6.3V"
MATERIAL"X6S"
PACK_TYPE"C0201"
TOLERANCE"20%"
PART_NUMBER"SP_CH4221MEE01"
LOCATION"C6710";
"2"
$PN"2"48;
"1"
$PN"1"46;
%"TAP"
"1","(-6550,850)","0","standard","I104";
;
CDS_LIB"standard"
BODY_TYPE"PLUMBING"
HDL_TAP"TRUE";
"B \NAC \NWC"8;
"S \NAC"
BN"15"61;
%"TAP"
"1","(-6550,1050)","0","standard","I105";
;
CDS_LIB"standard"
BODY_TYPE"PLUMBING"
HDL_TAP"TRUE";
"B \NAC \NWC"8;
"S \NAC"
BN"14"59;
%"TAP"
"1","(-6350,800)","0","standard","I106";
;
CDS_LIB"standard"
BODY_TYPE"PLUMBING"
HDL_TAP"TRUE";
"B \NAC \NWC"7;
"S \NAC"
BN"15"62;
%"TAP"
"1","(-6350,1000)","0","standard","I107";
;
CDS_LIB"standard"
BODY_TYPE"PLUMBING"
HDL_TAP"TRUE";
"B \NAC \NWC"7;
"S \NAC"
BN"14"60;
%"TAP"
"1","(-6550,1250)","0","standard","I108";
;
CDS_LIB"standard"
BODY_TYPE"PLUMBING"
HDL_TAP"TRUE";
"B \NAC \NWC"8;
"S \NAC"
BN"13"57;
%"TAP"
"1","(-6550,1450)","0","standard","I109";
;
CDS_LIB"standard"
BODY_TYPE"PLUMBING"
HDL_TAP"TRUE";
"B \NAC \NWC"8;
"S \NAC"
BN"12"55;
%"TAP"
"1","(-3300,1525)","2","standard","I11";
;
CDS_LIB"standard"
BODY_TYPE"PLUMBING"
HDL_TAP"TRUE";
"B \NAC \NWC"1;
"S \NAC"
BN"3"102;
%"TAP"
"1","(-6550,1650)","0","standard","I110";
;
CDS_LIB"standard"
BODY_TYPE"PLUMBING"
HDL_TAP"TRUE";
"B \NAC \NWC"8;
"S \NAC"
BN"11"53;
%"TAP"
"1","(-6550,1850)","0","standard","I111";
;
CDS_LIB"standard"
BODY_TYPE"PLUMBING"
HDL_TAP"TRUE";
"B \NAC \NWC"8;
"S \NAC"
BN"10"51;
%"TAP"
"1","(-6550,2050)","0","standard","I112";
;
CDS_LIB"standard"
BODY_TYPE"PLUMBING"
HDL_TAP"TRUE";
"B \NAC \NWC"8;
"S \NAC"
BN"9"49;
%"TAP"
"1","(-6350,1200)","0","standard","I113";
;
CDS_LIB"standard"
BODY_TYPE"PLUMBING"
HDL_TAP"TRUE";
"B \NAC \NWC"7;
"S \NAC"
BN"13"58;
%"TAP"
"1","(-6350,1400)","0","standard","I114";
;
CDS_LIB"standard"
BODY_TYPE"PLUMBING"
HDL_TAP"TRUE";
"B \NAC \NWC"7;
"S \NAC"
BN"12"56;
%"TAP"
"1","(-6350,1600)","0","standard","I115";
;
CDS_LIB"standard"
BODY_TYPE"PLUMBING"
HDL_TAP"TRUE";
"B \NAC \NWC"7;
"S \NAC"
BN"11"54;
%"TAP"
"1","(-6350,1800)","0","standard","I116";
;
CDS_LIB"standard"
BODY_TYPE"PLUMBING"
HDL_TAP"TRUE";
"B \NAC \NWC"7;
"S \NAC"
BN"10"52;
%"TAP"
"1","(-6350,2000)","0","standard","I117";
;
CDS_LIB"standard"
BODY_TYPE"PLUMBING"
HDL_TAP"TRUE";
"B \NAC \NWC"7;
"S \NAC"
BN"9"50;
%"TAP"
"1","(-6550,2250)","0","standard","I118";
;
CDS_LIB"standard"
BODY_TYPE"PLUMBING"
HDL_TAP"TRUE";
"B \NAC \NWC"8;
"S \NAC"
BN"8"45;
%"TAP"
"1","(-6350,2200)","0","standard","I119";
;
CDS_LIB"standard"
BODY_TYPE"PLUMBING"
HDL_TAP"TRUE";
"B \NAC \NWC"7;
"S \NAC"
BN"8"46;
%"TAP"
"1","(-3300,1725)","2","standard","I12";
;
CDS_LIB"standard"
BODY_TYPE"PLUMBING"
HDL_TAP"TRUE";
"B \NAC \NWC"1;
"S \NAC"
BN"2"101;
%"TAP"
"1","(-1875,3400)","0","standard","I120";
;
CDS_LIB"standard"
BODY_TYPE"PLUMBING"
HDL_TAP"TRUE";
"B \NAC \NWC"11;
"S \NAC"
BN"0"40;
%"TAP"
"1","(-1875,3750)","0","standard","I121";
;
CDS_LIB"standard"
BODY_TYPE"PLUMBING"
HDL_TAP"TRUE";
"B \NAC \NWC"11;
"S \NAC"
BN"1"21;
%"TAP"
"1","(-1875,4100)","0","standard","I122";
;
CDS_LIB"standard"
BODY_TYPE"PLUMBING"
HDL_TAP"TRUE";
"B \NAC \NWC"11;
"S \NAC"
BN"2"30;
%"TAP"
"1","(-1675,3300)","0","standard","I123";
;
CDS_LIB"standard"
BODY_TYPE"PLUMBING"
HDL_TAP"TRUE";
"B \NAC \NWC"10;
"S \NAC"
BN"0"43;
%"TAP"
"1","(-1675,3650)","0","standard","I124";
;
CDS_LIB"standard"
BODY_TYPE"PLUMBING"
HDL_TAP"TRUE";
"B \NAC \NWC"10;
"S \NAC"
BN"1"41;
%"TAP"
"1","(-1675,4000)","0","standard","I125";
;
CDS_LIB"standard"
BODY_TYPE"PLUMBING"
HDL_TAP"TRUE";
"B \NAC \NWC"10;
"S \NAC"
BN"2"42;
%"TAP"
"1","(-1875,4450)","0","standard","I128";
;
CDS_LIB"standard"
BODY_TYPE"PLUMBING"
HDL_TAP"TRUE";
"B \NAC \NWC"11;
"S \NAC"
BN"3"22;
%"TAP"
"1","(-1875,4800)","0","standard","I129";
;
CDS_LIB"standard"
BODY_TYPE"PLUMBING"
HDL_TAP"TRUE";
"B \NAC \NWC"11;
"S \NAC"
BN"4"24;
%"TAP"
"1","(-3300,1925)","2","standard","I13";
;
CDS_LIB"standard"
BODY_TYPE"PLUMBING"
HDL_TAP"TRUE";
"B \NAC \NWC"1;
"S \NAC"
BN"1"100;
%"TAP"
"1","(-1875,5150)","0","standard","I130";
;
CDS_LIB"standard"
BODY_TYPE"PLUMBING"
HDL_TAP"TRUE";
"B \NAC \NWC"11;
"S \NAC"
BN"5"23;
%"TAP"
"1","(-1675,4350)","0","standard","I131";
;
CDS_LIB"standard"
BODY_TYPE"PLUMBING"
HDL_TAP"TRUE";
"B \NAC \NWC"10;
"S \NAC"
BN"3"25;
%"TAP"
"1","(-1675,4700)","0","standard","I132";
;
CDS_LIB"standard"
BODY_TYPE"PLUMBING"
HDL_TAP"TRUE";
"B \NAC \NWC"10;
"S \NAC"
BN"4"26;
%"TAP"
"1","(-1675,5050)","0","standard","I133";
;
CDS_LIB"standard"
BODY_TYPE"PLUMBING"
HDL_TAP"TRUE";
"B \NAC \NWC"10;
"S \NAC"
BN"5"33;
%"TAP"
"1","(-1875,5500)","0","standard","I134";
;
CDS_LIB"standard"
BODY_TYPE"PLUMBING"
HDL_TAP"TRUE";
"B \NAC \NWC"11;
"S \NAC"
BN"6"32;
%"TAP"
"1","(-1875,5850)","0","standard","I135";
;
CDS_LIB"standard"
BODY_TYPE"PLUMBING"
HDL_TAP"TRUE";
"B \NAC \NWC"11;
"S \NAC"
BN"7"27;
%"TAP"
"1","(-1675,5400)","0","standard","I136";
;
CDS_LIB"standard"
BODY_TYPE"PLUMBING"
HDL_TAP"TRUE";
"B \NAC \NWC"10;
"S \NAC"
BN"6"29;
%"TAP"
"1","(-1675,5750)","0","standard","I137";
;
CDS_LIB"standard"
BODY_TYPE"PLUMBING"
HDL_TAP"TRUE";
"B \NAC \NWC"10;
"S \NAC"
BN"7"28;
%"TAP"
"1","(-3050,1575)","2","standard","I14";
;
CDS_LIB"standard"
BODY_TYPE"PLUMBING"
HDL_TAP"TRUE";
"B \NAC \NWC"3;
"S \NAC"
BN"3"89;
%"TAP"
"1","(-7825,1050)","2","standard","I140";
;
CDS_LIB"standard"
BODY_TYPE"PLUMBING"
HDL_TAP"TRUE";
"B \NAC \NWC"6;
"S \NAC"
BN"14"73;
%"TAP"
"1","(-8075,2000)","2","standard","I141";
;
CDS_LIB"standard"
BODY_TYPE"PLUMBING"
HDL_TAP"TRUE";
"B \NAC \NWC"5;
"S \NAC"
BN"9"66;
%"PT5161LRS"
"11","(-2600,4600)","0","pure_quanta","I142";
;
LOCATION"U6016"
$SEC"11"
CDS_SEC"11"
MATERIAL"IC"
VALUE"PT5161LRS"
PART_TYPE"SMLF"
NEEDS_NO_SIZE"TRUE"
CDS_LMAN_SYM_OUTLINE"-350,1450,300,-1400"
CDS_LIB"pure_quanta"
PART_NUMBER"AJ051610U03";
"B_PETN15"
$PN"EW10"43;
"B_PETP15"
$PN"EU7"40;
"B_PETN14"
$PN"EM10"41;
"B_PETP14"
$PN"EK7"21;
"B_PETN13"
$PN"EE10"42;
"B_PETP13"
$PN"EC7"30;
"B_PETN12"
$PN"DV10"25;
"B_PETP12"
$PN"DT7"22;
"B_PETN11"
$PN"DL10"26;
"B_PETP11"
$PN"DJ7"24;
"B_PETN10"
$PN"DD10"33;
"B_PETP10"
$PN"DB7"23;
"B_PETN9"
$PN"CU10"29;
"B_PETP9"
$PN"CR7"32;
"B_PETN8"
$PN"CK10"28;
"B_PETP8"
$PN"CH7"27;
%"TAP"
"1","(-3050,1775)","2","standard","I15";
;
CDS_LIB"standard"
BODY_TYPE"PLUMBING"
HDL_TAP"TRUE";
"B \NAC \NWC"3;
"S \NAC"
BN"2"88;
%"TAP"
"1","(-3050,1975)","2","standard","I16";
;
CDS_LIB"standard"
BODY_TYPE"PLUMBING"
HDL_TAP"TRUE";
"B \NAC \NWC"3;
"S \NAC"
BN"1"87;
%"Q_CAP_DIFFBUS"
"2","(-2325,725)","2","pure_quanta","I17";
;
LOCATION"C6708"
$SEC"1"
CDS_SEC"1"
VALUE"DIFF BUS_0.22UF"
TOLERANCE"20%"
PACK_TYPE"C0201"
MATERIAL"X6S"
VOLTAGE"6.3V"
PIN_NAMES_ROTATE"TRUE"
CDS_LIB"pure_quanta"
CDS_LMAN_SYM_OUTLINE"-25,50,25,-50"
PART_NUMBER"SP_CH4221MEE01"
LOCATION"C6708";
"2"
$PN"2"106;
"1"
$PN"1"96;
%"Q_CAP_DIFFBUS"
"2","(-2325,775)","2","pure_quanta","I18";
;
LOCATION"C6707"
$SEC"1"
CDS_SEC"1"
VALUE"DIFF BUS_0.22UF"
TOLERANCE"20%"
PACK_TYPE"C0201"
MATERIAL"X6S"
VOLTAGE"6.3V"
PIN_NAMES_ROTATE"TRUE"
CDS_LIB"pure_quanta"
CDS_LMAN_SYM_OUTLINE"-25,50,25,-50"
PART_NUMBER"SP_CH4221MEE01"
LOCATION"C6707";
"2"
$PN"2"99;
"1"
$PN"1"95;
%"Q_CAP_DIFFBUS"
"2","(-2325,925)","2","pure_quanta","I19";
;
LOCATION"C6706"
$SEC"1"
CDS_SEC"1"
VALUE"DIFF BUS_0.22UF"
TOLERANCE"20%"
PACK_TYPE"C0201"
MATERIAL"X6S"
VOLTAGE"6.3V"
PIN_NAMES_ROTATE"TRUE"
CDS_LIB"pure_quanta"
CDS_LMAN_SYM_OUTLINE"-25,50,25,-50"
PART_NUMBER"SP_CH4221MEE01"
LOCATION"C6706";
"2"
$PN"2"105;
"1"
$PN"1"94;
%"Q_CAP_DIFFBUS"
"2","(-2325,975)","2","pure_quanta","I20";
;
LOCATION"C6705"
$SEC"1"
CDS_SEC"1"
VALUE"DIFF BUS_0.22UF"
TOLERANCE"20%"
PACK_TYPE"C0201"
MATERIAL"X6S"
VOLTAGE"6.3V"
PIN_NAMES_ROTATE"TRUE"
CDS_LMAN_SYM_OUTLINE"-25,50,25,-50"
CDS_LIB"pure_quanta"
PART_NUMBER"SP_CH4221MEE01"
LOCATION"C6705";
"2"
$PN"2"98;
"1"
$PN"1"93;
%"Q_CAP_DIFFBUS"
"2","(-2325,1125)","2","pure_quanta","I21";
;
LOCATION"C6704"
$SEC"1"
CDS_SEC"1"
VALUE"DIFF BUS_0.22UF"
TOLERANCE"20%"
PACK_TYPE"C0201"
MATERIAL"X6S"
VOLTAGE"6.3V"
PIN_NAMES_ROTATE"TRUE"
CDS_LIB"pure_quanta"
CDS_LMAN_SYM_OUTLINE"-25,50,25,-50"
PART_NUMBER"SP_CH4221MEE01"
LOCATION"C6704";
"2"
$PN"2"104;
"1"
$PN"1"92;
%"Q_CAP_DIFFBUS"
"2","(-2325,1175)","2","pure_quanta","I22";
;
LOCATION"C6703"
$SEC"1"
CDS_SEC"1"
VALUE"DIFF BUS_0.22UF"
TOLERANCE"20%"
PACK_TYPE"C0201"
MATERIAL"X6S"
VOLTAGE"6.3V"
PIN_NAMES_ROTATE"TRUE"
CDS_LIB"pure_quanta"
CDS_LMAN_SYM_OUTLINE"-25,50,25,-50"
PART_NUMBER"SP_CH4221MEE01"
LOCATION"C6703";
"2"
$PN"2"97;
"1"
$PN"1"91;
%"Q_CAP_DIFFBUS"
"2","(-2325,1325)","2","pure_quanta","I23";
;
LOCATION"C6702"
$SEC"1"
CDS_SEC"1"
VALUE"DIFF BUS_0.22UF"
TOLERANCE"20%"
PACK_TYPE"C0201"
MATERIAL"X6S"
VOLTAGE"6.3V"
PIN_NAMES_ROTATE"TRUE"
CDS_LMAN_SYM_OUTLINE"-25,50,25,-50"
CDS_LIB"pure_quanta"
PART_NUMBER"SP_CH4221MEE01"
LOCATION"C6702";
"2"
$PN"2"103;
"1"
$PN"1"85;
%"Q_CAP_DIFFBUS"
"2","(-2325,1375)","2","pure_quanta","I24";
;
LOCATION"C6701"
$SEC"1"
CDS_SEC"1"
VALUE"DIFF BUS_0.22UF"
TOLERANCE"20%"
PACK_TYPE"C0201"
MATERIAL"X6S"
VOLTAGE"6.3V"
PIN_NAMES_ROTATE"TRUE"
CDS_LMAN_SYM_OUTLINE"-25,50,25,-50"
CDS_LIB"pure_quanta"
PART_NUMBER"SP_CH4221MEE01"
LOCATION"C6701";
"2"
$PN"2"90;
"1"
$PN"1"84;
%"Q_CAP_DIFFBUS"
"2","(-2325,1575)","2","pure_quanta","I25";
;
LOCATION"C6699"
$SEC"1"
CDS_SEC"1"
VALUE"DIFF BUS_0.22UF"
TOLERANCE"20%"
PACK_TYPE"C0201"
MATERIAL"X6S"
VOLTAGE"6.3V"
PIN_NAMES_ROTATE"TRUE"
CDS_LIB"pure_quanta"
CDS_LMAN_SYM_OUTLINE"-25,50,25,-50"
PART_NUMBER"SP_CH4221MEE01"
LOCATION"C6699";
"2"
$PN"2"89;
"1"
$PN"1"82;
%"Q_CAP_DIFFBUS"
"2","(-2325,1525)","2","pure_quanta","I26";
;
LOCATION"C6700"
$SEC"1"
CDS_SEC"1"
VALUE"DIFF BUS_0.22UF"
TOLERANCE"20%"
PACK_TYPE"C0201"
MATERIAL"X6S"
VOLTAGE"6.3V"
PIN_NAMES_ROTATE"TRUE"
CDS_LIB"pure_quanta"
CDS_LMAN_SYM_OUTLINE"-25,50,25,-50"
PART_NUMBER"SP_CH4221MEE01"
LOCATION"C6700";
"2"
$PN"2"102;
"1"
$PN"1"83;
%"Q_CAP_DIFFBUS"
"2","(-2325,1725)","2","pure_quanta","I27";
;
LOCATION"C6698"
$SEC"1"
CDS_SEC"1"
VALUE"DIFF BUS_0.22UF"
TOLERANCE"20%"
PACK_TYPE"C0201"
MATERIAL"X6S"
VOLTAGE"6.3V"
PIN_NAMES_ROTATE"TRUE"
CDS_LIB"pure_quanta"
CDS_LMAN_SYM_OUTLINE"-25,50,25,-50"
PART_NUMBER"SP_CH4221MEE01"
LOCATION"C6698";
"2"
$PN"2"101;
"1"
$PN"1"107;
%"Q_CAP_DIFFBUS"
"2","(-2325,1925)","2","pure_quanta","I28";
;
LOCATION"C6696"
$SEC"1"
CDS_SEC"1"
VALUE"DIFF BUS_0.22UF"
TOLERANCE"20%"
PACK_TYPE"C0201"
MATERIAL"X6S"
VOLTAGE"6.3V"
PIN_NAMES_ROTATE"TRUE"
CDS_LIB"pure_quanta"
CDS_LMAN_SYM_OUTLINE"-25,50,25,-50"
PART_NUMBER"SP_CH4221MEE01"
LOCATION"C6696";
"2"
$PN"2"100;
"1"
$PN"1"80;
%"Q_CAP_DIFFBUS"
"2","(-2325,1975)","2","pure_quanta","I29";
;
LOCATION"C6695"
$SEC"1"
CDS_SEC"1"
VALUE"DIFF BUS_0.22UF"
TOLERANCE"20%"
PACK_TYPE"C0201"
MATERIAL"X6S"
VOLTAGE"6.3V"
PIN_NAMES_ROTATE"TRUE"
CDS_LIB"pure_quanta"
CDS_LMAN_SYM_OUTLINE"-25,50,25,-50"
PART_NUMBER"SP_CH4221MEE01"
LOCATION"C6695";
"2"
$PN"2"87;
"1"
$PN"1"79;
%"TAP"
"1","(-3300,725)","2","standard","I3";
;
CDS_LIB"standard"
BODY_TYPE"PLUMBING"
HDL_TAP"TRUE";
"B \NAC \NWC"1;
"S \NAC"
BN"7"106;
%"Q_CAP_DIFFBUS"
"2","(-2325,1775)","2","pure_quanta","I30";
;
LOCATION"C6697"
$SEC"1"
CDS_SEC"1"
VALUE"DIFF BUS_0.22UF"
TOLERANCE"20%"
PACK_TYPE"C0201"
MATERIAL"X6S"
VOLTAGE"6.3V"
PIN_NAMES_ROTATE"TRUE"
CDS_LIB"pure_quanta"
CDS_LMAN_SYM_OUTLINE"-25,50,25,-50"
PART_NUMBER"SP_CH4221MEE01"
LOCATION"C6697";
"2"
$PN"2"88;
"1"
$PN"1"81;
%"TAP"
"1","(-3300,2125)","2","standard","I31";
;
CDS_LIB"standard"
BODY_TYPE"PLUMBING"
HDL_TAP"TRUE";
"B \NAC \NWC"1;
"S \NAC"
BN"0"108;
%"TAP"
"1","(-3050,2175)","2","standard","I32";
;
CDS_LIB"standard"
BODY_TYPE"PLUMBING"
HDL_TAP"TRUE";
"B \NAC \NWC"3;
"S \NAC"
BN"0"86;
%"PT5161LRS"
"10","(-7775,4625)","0","pure_quanta","I33";
;
LOCATION"U6016"
$SEC"10"
CDS_SEC"10"
VALUE"PT5161LRS"
MATERIAL"IC"
PART_TYPE"SMLF"
CDS_LIB"pure_quanta"
CDS_LMAN_SYM_OUTLINE"-350,1450,300,-1400"
NEEDS_NO_SIZE"TRUE"
PART_NUMBER"AJ051610U03";
"B_PETN7"
$PN"CC10"44;
"B_PETP7"
$PN"CA7"35;
"B_PETN6"
$PN"BT10"16;
"B_PETP6"
$PN"BP7"13;
"B_PETN5"
$PN"BJ10"15;
"B_PETP5"
$PN"BG7"14;
"B_PETN4"
$PN"BB10"18;
"B_PETP4"
$PN"AY7"31;
"B_PETN3"
$PN"AR10"36;
"B_PETP3"
$PN"AN7"17;
"B_PETN2"
$PN"AH10"37;
"B_PETP2"
$PN"AF7"38;
"B_PETN1"
$PN"AA10"39;
"B_PETP1"
$PN"W7"19;
"B_PETN0"
$PN"P10"34;
"B_PETP0"
$PN"M7"20;
%"Q_CAP_DIFFBUS"
"2","(-2325,2175)","2","pure_quanta","I34";
;
LOCATION"C6693"
$SEC"1"
CDS_SEC"1"
VOLTAGE"6.3V"
TOLERANCE"20%"
VALUE"DIFF BUS_0.22UF"
MATERIAL"X6S"
PACK_TYPE"C0201"
PIN_NAMES_ROTATE"TRUE"
CDS_LMAN_SYM_OUTLINE"-25,50,25,-50"
CDS_LIB"pure_quanta"
PART_NUMBER"SP_CH4221MEE01"
LOCATION"C6693";
"2"
$PN"2"86;
"1"
$PN"1"77;
%"Q_CAP_DIFFBUS"
"2","(-2325,2125)","2","pure_quanta","I35";
;
LOCATION"C6694"
$SEC"1"
CDS_SEC"1"
VALUE"DIFF BUS_0.22UF"
TOLERANCE"20%"
PACK_TYPE"C0201"
MATERIAL"X6S"
VOLTAGE"6.3V"
PIN_NAMES_ROTATE"TRUE"
CDS_LIB"pure_quanta"
CDS_LMAN_SYM_OUTLINE"-25,50,25,-50"
PART_NUMBER"SP_CH4221MEE01"
LOCATION"C6694";
"2"
$PN"2"108;
"1"
$PN"1"78;
%"TAP"
"1","(-7050,3425)","0","standard","I36";
;
CDS_LIB"standard"
BODY_TYPE"PLUMBING"
HDL_TAP"TRUE";
"B \NAC \NWC"12;
"S \NAC"
BN"8"35;
%"TAP"
"1","(-7050,3775)","0","standard","I37";
;
CDS_LIB"standard"
BODY_TYPE"PLUMBING"
HDL_TAP"TRUE";
"B \NAC \NWC"12;
"S \NAC"
BN"9"13;
%"TAP"
"1","(-7050,4125)","0","standard","I38";
;
CDS_LIB"standard"
BODY_TYPE"PLUMBING"
HDL_TAP"TRUE";
"B \NAC \NWC"12;
"S \NAC"
BN"10"14;
%"TAP"
"1","(-6850,3325)","0","standard","I39";
;
CDS_LIB"standard"
BODY_TYPE"PLUMBING"
HDL_TAP"TRUE";
"B \NAC \NWC"9;
"S \NAC"
BN"8"44;
%"TAP"
"1","(-3300,925)","2","standard","I4";
;
CDS_LIB"standard"
BODY_TYPE"PLUMBING"
HDL_TAP"TRUE";
"B \NAC \NWC"1;
"S \NAC"
BN"6"105;
%"TAP"
"1","(-6850,3675)","0","standard","I40";
;
CDS_LIB"standard"
BODY_TYPE"PLUMBING"
HDL_TAP"TRUE";
"B \NAC \NWC"9;
"S \NAC"
BN"9"16;
%"TAP"
"1","(-6850,4025)","0","standard","I41";
;
CDS_LIB"standard"
BODY_TYPE"PLUMBING"
HDL_TAP"TRUE";
"B \NAC \NWC"9;
"S \NAC"
BN"10"15;
%"TAP"
"1","(-1575,725)","0","standard","I42";
;
CDS_LIB"standard"
BODY_TYPE"PLUMBING"
HDL_TAP"TRUE";
"B \NAC \NWC"2;
"S \NAC"
BN"7"96;
%"TAP"
"1","(-1775,775)","0","standard","I43";
;
CDS_LIB"standard"
BODY_TYPE"PLUMBING"
HDL_TAP"TRUE";
"B \NAC \NWC"4;
"S \NAC"
BN"7"95;
%"TAP"
"1","(-1775,975)","0","standard","I44";
;
CDS_LIB"standard"
BODY_TYPE"PLUMBING"
HDL_TAP"TRUE";
"B \NAC \NWC"4;
"S \NAC"
BN"6"93;
%"TAP"
"1","(-1575,925)","0","standard","I45";
;
CDS_LIB"standard"
BODY_TYPE"PLUMBING"
HDL_TAP"TRUE";
"B \NAC \NWC"2;
"S \NAC"
BN"6"94;
%"TAP"
"1","(-1775,1175)","0","standard","I46";
;
CDS_LIB"standard"
BODY_TYPE"PLUMBING"
HDL_TAP"TRUE";
"B \NAC \NWC"4;
"S \NAC"
BN"5"91;
%"TAP"
"1","(-1575,1125)","0","standard","I47";
;
CDS_LIB"standard"
BODY_TYPE"PLUMBING"
HDL_TAP"TRUE";
"B \NAC \NWC"2;
"S \NAC"
BN"5"92;
%"TAP"
"1","(-1775,1375)","0","standard","I48";
;
CDS_LIB"standard"
BODY_TYPE"PLUMBING"
HDL_TAP"TRUE";
"B \NAC \NWC"4;
"S \NAC"
BN"4"84;
%"TAP"
"1","(-1575,1325)","0","standard","I49";
;
CDS_LIB"standard"
BODY_TYPE"PLUMBING"
HDL_TAP"TRUE";
"B \NAC \NWC"2;
"S \NAC"
BN"4"85;
%"TAP"
"1","(-3050,775)","2","standard","I5";
;
CDS_LIB"standard"
BODY_TYPE"PLUMBING"
HDL_TAP"TRUE";
"B \NAC \NWC"3;
"S \NAC"
BN"7"99;
%"TAP"
"1","(-1775,1575)","0","standard","I50";
;
CDS_LIB"standard"
BODY_TYPE"PLUMBING"
HDL_TAP"TRUE";
"B \NAC \NWC"4;
"S \NAC"
BN"3"82;
%"TAP"
"1","(-1575,1725)","0","standard","I51";
;
CDS_LIB"standard"
BODY_TYPE"PLUMBING"
HDL_TAP"TRUE";
"B \NAC \NWC"2;
"S \NAC"
BN"2"107;
%"TAP"
"1","(-1575,1525)","0","standard","I52";
;
CDS_LIB"standard"
BODY_TYPE"PLUMBING"
HDL_TAP"TRUE";
"B \NAC \NWC"2;
"S \NAC"
BN"3"83;
%"TAP"
"1","(-1775,1775)","0","standard","I53";
;
CDS_LIB"standard"
BODY_TYPE"PLUMBING"
HDL_TAP"TRUE";
"B \NAC \NWC"4;
"S \NAC"
BN"2"81;
%"TAP"
"1","(-1775,1975)","0","standard","I54";
;
CDS_LIB"standard"
BODY_TYPE"PLUMBING"
HDL_TAP"TRUE";
"B \NAC \NWC"4;
"S \NAC"
BN"1"79;
%"TAP"
"1","(-1575,1925)","0","standard","I55";
;
CDS_LIB"standard"
BODY_TYPE"PLUMBING"
HDL_TAP"TRUE";
"B \NAC \NWC"2;
"S \NAC"
BN"1"80;
%"TAP"
"1","(-1775,2175)","0","standard","I56";
;
CDS_LIB"standard"
BODY_TYPE"PLUMBING"
HDL_TAP"TRUE";
"B \NAC \NWC"4;
"S \NAC"
BN"0"77;
%"TAP"
"1","(-1575,2125)","0","standard","I57";
;
CDS_LIB"standard"
BODY_TYPE"PLUMBING"
HDL_TAP"TRUE";
"B \NAC \NWC"2;
"S \NAC"
BN"0"78;
%"TAP"
"1","(-3050,975)","2","standard","I6";
;
CDS_LIB"standard"
BODY_TYPE"PLUMBING"
HDL_TAP"TRUE";
"B \NAC \NWC"3;
"S \NAC"
BN"6"98;
%"TAP"
"1","(-7050,4475)","0","standard","I62";
;
CDS_LIB"standard"
BODY_TYPE"PLUMBING"
HDL_TAP"TRUE";
"B \NAC \NWC"12;
"S \NAC"
BN"11"31;
%"TAP"
"1","(-7050,4825)","0","standard","I63";
;
CDS_LIB"standard"
BODY_TYPE"PLUMBING"
HDL_TAP"TRUE";
"B \NAC \NWC"12;
"S \NAC"
BN"12"17;
%"TAP"
"1","(-6850,4375)","0","standard","I64";
;
CDS_LIB"standard"
BODY_TYPE"PLUMBING"
HDL_TAP"TRUE";
"B \NAC \NWC"9;
"S \NAC"
BN"11"18;
%"TAP"
"1","(-6850,4725)","0","standard","I65";
;
CDS_LIB"standard"
BODY_TYPE"PLUMBING"
HDL_TAP"TRUE";
"B \NAC \NWC"9;
"S \NAC"
BN"12"36;
%"TAP"
"1","(-6850,5075)","0","standard","I66";
;
CDS_LIB"standard"
BODY_TYPE"PLUMBING"
HDL_TAP"TRUE";
"B \NAC \NWC"9;
"S \NAC"
BN"13"37;
%"TAP"
"1","(-7050,5175)","0","standard","I67";
;
CDS_LIB"standard"
BODY_TYPE"PLUMBING"
HDL_TAP"TRUE";
"B \NAC \NWC"12;
"S \NAC"
BN"13"38;
%"TAP"
"1","(-7050,5525)","0","standard","I68";
;
CDS_LIB"standard"
BODY_TYPE"PLUMBING"
HDL_TAP"TRUE";
"B \NAC \NWC"12;
"S \NAC"
BN"14"19;
%"TAP"
"1","(-7050,5875)","0","standard","I69";
;
CDS_LIB"standard"
BODY_TYPE"PLUMBING"
HDL_TAP"TRUE";
"B \NAC \NWC"12;
"S \NAC"
BN"15"20;
%"TAP"
"1","(-3300,1125)","2","standard","I7";
;
CDS_LIB"standard"
BODY_TYPE"PLUMBING"
HDL_TAP"TRUE";
"B \NAC \NWC"1;
"S \NAC"
BN"5"104;
%"TAP"
"1","(-6850,5425)","0","standard","I70";
;
CDS_LIB"standard"
BODY_TYPE"PLUMBING"
HDL_TAP"TRUE";
"B \NAC \NWC"9;
"S \NAC"
BN"14"39;
%"TAP"
"1","(-6850,5775)","0","standard","I71";
;
CDS_LIB"standard"
BODY_TYPE"PLUMBING"
HDL_TAP"TRUE";
"B \NAC \NWC"9;
"S \NAC"
BN"15"34;
%"TAP"
"1","(-8075,800)","2","standard","I74";
;
CDS_LIB"standard"
BODY_TYPE"PLUMBING"
HDL_TAP"TRUE";
"B \NAC \NWC"5;
"S \NAC"
BN"15"76;
%"TAP"
"1","(-8075,1000)","2","standard","I75";
;
CDS_LIB"standard"
BODY_TYPE"PLUMBING"
HDL_TAP"TRUE";
"B \NAC \NWC"5;
"S \NAC"
BN"14"75;
%"TAP"
"1","(-8075,1200)","2","standard","I76";
;
CDS_LIB"standard"
BODY_TYPE"PLUMBING"
HDL_TAP"TRUE";
"B \NAC \NWC"5;
"S \NAC"
BN"13"71;
%"TAP"
"1","(-8075,1600)","2","standard","I77";
;
CDS_LIB"standard"
BODY_TYPE"PLUMBING"
HDL_TAP"TRUE";
"B \NAC \NWC"5;
"S \NAC"
BN"11"67;
%"TAP"
"1","(-8075,1400)","2","standard","I78";
;
CDS_LIB"standard"
BODY_TYPE"PLUMBING"
HDL_TAP"TRUE";
"B \NAC \NWC"5;
"S \NAC"
BN"12"72;
%"TAP"
"1","(-8075,1800)","2","standard","I79";
;
CDS_LIB"standard"
BODY_TYPE"PLUMBING"
HDL_TAP"TRUE";
"B \NAC \NWC"5;
"S \NAC"
BN"10"68;
%"TAP"
"1","(-3300,1325)","2","standard","I8";
;
CDS_LIB"standard"
BODY_TYPE"PLUMBING"
HDL_TAP"TRUE";
"B \NAC \NWC"1;
"S \NAC"
BN"4"103;
%"TAP"
"1","(-7825,850)","2","standard","I80";
;
CDS_LIB"standard"
BODY_TYPE"PLUMBING"
HDL_TAP"TRUE";
"B \NAC \NWC"6;
"S \NAC"
BN"15"74;
%"Q_CAP_DIFFBUS"
"2","(-7100,800)","2","pure_quanta","I81";
;
LOCATION"C6724"
$SEC"1"
CDS_SEC"1"
VALUE"DIFF BUS_0.22UF"
CDS_LMAN_SYM_OUTLINE"-25,50,25,-50"
CDS_LIB"pure_quanta"
PIN_NAMES_ROTATE"TRUE"
VOLTAGE"6.3V"
MATERIAL"X6S"
PACK_TYPE"C0201"
TOLERANCE"20%"
PART_NUMBER"SP_CH4221MEE01"
LOCATION"C6724";
"2"
$PN"2"76;
"1"
$PN"1"62;
%"Q_CAP_DIFFBUS"
"2","(-7100,850)","2","pure_quanta","I82";
;
LOCATION"C6723"
$SEC"1"
CDS_SEC"1"
VALUE"DIFF BUS_0.22UF"
CDS_LMAN_SYM_OUTLINE"-25,50,25,-50"
CDS_LIB"pure_quanta"
PIN_NAMES_ROTATE"TRUE"
VOLTAGE"6.3V"
MATERIAL"X6S"
PACK_TYPE"C0201"
TOLERANCE"20%"
PART_NUMBER"SP_CH4221MEE01"
LOCATION"C6723";
"2"
$PN"2"74;
"1"
$PN"1"61;
%"Q_CAP_DIFFBUS"
"2","(-7100,1000)","2","pure_quanta","I83";
;
LOCATION"C6722"
$SEC"1"
CDS_SEC"1"
VALUE"DIFF BUS_0.22UF"
CDS_LMAN_SYM_OUTLINE"-25,50,25,-50"
CDS_LIB"pure_quanta"
PIN_NAMES_ROTATE"TRUE"
VOLTAGE"6.3V"
MATERIAL"X6S"
PACK_TYPE"C0201"
TOLERANCE"20%"
PART_NUMBER"SP_CH4221MEE01"
LOCATION"C6722";
"2"
$PN"2"75;
"1"
$PN"1"60;
%"Q_CAP_DIFFBUS"
"2","(-7100,1050)","2","pure_quanta","I84";
;
LOCATION"C6721"
$SEC"1"
CDS_SEC"1"
VALUE"DIFF BUS_0.22UF"
CDS_LIB"pure_quanta"
CDS_LMAN_SYM_OUTLINE"-25,50,25,-50"
PIN_NAMES_ROTATE"TRUE"
VOLTAGE"6.3V"
MATERIAL"X6S"
PACK_TYPE"C0201"
TOLERANCE"20%"
PART_NUMBER"SP_CH4221MEE01"
LOCATION"C6721";
"2"
$PN"2"73;
"1"
$PN"1"59;
%"TAP"
"1","(-7825,1250)","2","standard","I85";
;
CDS_LIB"standard"
BODY_TYPE"PLUMBING"
HDL_TAP"TRUE";
"B \NAC \NWC"6;
"S \NAC"
BN"13"70;
%"TAP"
"1","(-7825,1450)","2","standard","I86";
;
CDS_LIB"standard"
BODY_TYPE"PLUMBING"
HDL_TAP"TRUE";
"B \NAC \NWC"6;
"S \NAC"
BN"12"69;
%"TAP"
"1","(-7825,1650)","2","standard","I87";
;
CDS_LIB"standard"
BODY_TYPE"PLUMBING"
HDL_TAP"TRUE";
"B \NAC \NWC"6;
"S \NAC"
BN"11"65;
%"TAP"
"1","(-7825,1850)","2","standard","I88";
;
CDS_LIB"standard"
BODY_TYPE"PLUMBING"
HDL_TAP"TRUE";
"B \NAC \NWC"6;
"S \NAC"
BN"10"64;
%"TAP"
"1","(-7825,2050)","2","standard","I89";
;
CDS_LIB"standard"
BODY_TYPE"PLUMBING"
HDL_TAP"TRUE";
"B \NAC \NWC"6;
"S \NAC"
BN"9"63;
%"TAP"
"1","(-3050,1175)","2","standard","I9";
;
CDS_LIB"standard"
BODY_TYPE"PLUMBING"
HDL_TAP"TRUE";
"B \NAC \NWC"3;
"S \NAC"
BN"5"97;
%"Q_CAP_DIFFBUS"
"2","(-7100,1200)","2","pure_quanta","I90";
;
LOCATION"C6720"
$SEC"1"
CDS_SEC"1"
VALUE"DIFF BUS_0.22UF"
CDS_LMAN_SYM_OUTLINE"-25,50,25,-50"
CDS_LIB"pure_quanta"
PIN_NAMES_ROTATE"TRUE"
VOLTAGE"6.3V"
MATERIAL"X6S"
PACK_TYPE"C0201"
TOLERANCE"20%"
PART_NUMBER"SP_CH4221MEE01"
LOCATION"C6720";
"2"
$PN"2"71;
"1"
$PN"1"58;
%"Q_CAP_DIFFBUS"
"2","(-7100,1250)","2","pure_quanta","I91";
;
LOCATION"C6719"
$SEC"1"
CDS_SEC"1"
VALUE"DIFF BUS_0.22UF"
CDS_LMAN_SYM_OUTLINE"-25,50,25,-50"
CDS_LIB"pure_quanta"
PIN_NAMES_ROTATE"TRUE"
VOLTAGE"6.3V"
MATERIAL"X6S"
PACK_TYPE"C0201"
TOLERANCE"20%"
PART_NUMBER"SP_CH4221MEE01"
LOCATION"C6719";
"2"
$PN"2"70;
"1"
$PN"1"57;
%"Q_CAP_DIFFBUS"
"2","(-7100,1400)","2","pure_quanta","I92";
;
LOCATION"C6718"
$SEC"1"
CDS_SEC"1"
VALUE"DIFF BUS_0.22UF"
CDS_LIB"pure_quanta"
CDS_LMAN_SYM_OUTLINE"-25,50,25,-50"
PIN_NAMES_ROTATE"TRUE"
VOLTAGE"6.3V"
MATERIAL"X6S"
PACK_TYPE"C0201"
TOLERANCE"20%"
PART_NUMBER"SP_CH4221MEE01"
LOCATION"C6718";
"2"
$PN"2"72;
"1"
$PN"1"56;
%"Q_CAP_DIFFBUS"
"2","(-7100,1450)","2","pure_quanta","I93";
;
LOCATION"C6717"
$SEC"1"
CDS_SEC"1"
VALUE"DIFF BUS_0.22UF"
CDS_LIB"pure_quanta"
CDS_LMAN_SYM_OUTLINE"-25,50,25,-50"
PIN_NAMES_ROTATE"TRUE"
VOLTAGE"6.3V"
MATERIAL"X6S"
PACK_TYPE"C0201"
TOLERANCE"20%"
PART_NUMBER"SP_CH4221MEE01"
LOCATION"C6717";
"2"
$PN"2"69;
"1"
$PN"1"55;
%"Q_CAP_DIFFBUS"
"2","(-7100,1600)","2","pure_quanta","I94";
;
LOCATION"C6716"
$SEC"1"
CDS_SEC"1"
VALUE"DIFF BUS_0.22UF"
CDS_LMAN_SYM_OUTLINE"-25,50,25,-50"
CDS_LIB"pure_quanta"
PIN_NAMES_ROTATE"TRUE"
VOLTAGE"6.3V"
MATERIAL"X6S"
PACK_TYPE"C0201"
TOLERANCE"20%"
PART_NUMBER"SP_CH4221MEE01"
LOCATION"C6716";
"2"
$PN"2"67;
"1"
$PN"1"54;
%"Q_CAP_DIFFBUS"
"2","(-7100,1650)","2","pure_quanta","I95";
;
LOCATION"C6715"
$SEC"1"
CDS_SEC"1"
VALUE"DIFF BUS_0.22UF"
CDS_LMAN_SYM_OUTLINE"-25,50,25,-50"
CDS_LIB"pure_quanta"
PIN_NAMES_ROTATE"TRUE"
VOLTAGE"6.3V"
MATERIAL"X6S"
PACK_TYPE"C0201"
TOLERANCE"20%"
PART_NUMBER"SP_CH4221MEE01"
LOCATION"C6715";
"2"
$PN"2"65;
"1"
$PN"1"53;
%"Q_CAP_DIFFBUS"
"2","(-7100,1800)","2","pure_quanta","I96";
;
LOCATION"C6714"
$SEC"1"
CDS_SEC"1"
VALUE"DIFF BUS_0.22UF"
CDS_LMAN_SYM_OUTLINE"-25,50,25,-50"
CDS_LIB"pure_quanta"
PIN_NAMES_ROTATE"TRUE"
VOLTAGE"6.3V"
MATERIAL"X6S"
PACK_TYPE"C0201"
TOLERANCE"20%"
PART_NUMBER"SP_CH4221MEE01"
LOCATION"C6714";
"2"
$PN"2"68;
"1"
$PN"1"52;
%"Q_CAP_DIFFBUS"
"2","(-7100,1850)","2","pure_quanta","I97";
;
LOCATION"C6713"
$SEC"1"
CDS_SEC"1"
VALUE"DIFF BUS_0.22UF"
CDS_LMAN_SYM_OUTLINE"-25,50,25,-50"
CDS_LIB"pure_quanta"
PIN_NAMES_ROTATE"TRUE"
VOLTAGE"6.3V"
MATERIAL"X6S"
PACK_TYPE"C0201"
TOLERANCE"20%"
PART_NUMBER"SP_CH4221MEE01"
LOCATION"C6713";
"2"
$PN"2"64;
"1"
$PN"1"51;
%"Q_CAP_DIFFBUS"
"2","(-7100,2000)","2","pure_quanta","I98";
;
LOCATION"C6712"
$SEC"1"
CDS_SEC"1"
VALUE"DIFF BUS_0.22UF"
CDS_LMAN_SYM_OUTLINE"-25,50,25,-50"
CDS_LIB"pure_quanta"
PIN_NAMES_ROTATE"TRUE"
VOLTAGE"6.3V"
MATERIAL"X6S"
PACK_TYPE"C0201"
TOLERANCE"20%"
PART_NUMBER"SP_CH4221MEE01"
LOCATION"C6712";
"2"
$PN"2"66;
"1"
$PN"1"50;
%"Q_CAP_DIFFBUS"
"2","(-7100,2050)","2","pure_quanta","I99";
;
LOCATION"C6711"
$SEC"1"
CDS_SEC"1"
VALUE"DIFF BUS_0.22UF"
CDS_LMAN_SYM_OUTLINE"-25,50,25,-50"
CDS_LIB"pure_quanta"
PIN_NAMES_ROTATE"TRUE"
VOLTAGE"6.3V"
MATERIAL"X6S"
PACK_TYPE"C0201"
TOLERANCE"20%"
PART_NUMBER"SP_CH4221MEE01"
LOCATION"C6711";
"2"
$PN"2"63;
"1"
$PN"1"49;
END.
